FILE_TYPE = CONNECTIVITY;
{Allegro Design Entry HDL 17.2-2016 S081 (4005846) 1/11/2022}
"PAGE_NUMBER" = 169;
0"NC";
1"DMI_CPU0_PCH_TX_DP<7:0>";
2"DMI_CPU0_PCH_RX_C_DP<7:0>";
3"DMI_CPU0_PCH_RX_DP<7:0>";
4"DMI_CPU0_PCH_RX_DN<7:0>";
5"DMI_CPU0_PCH_TX_DN<7:0>";
6"DMI_CPU0_PCH_TX_C_DN<7:0>";
7"DMI_CPU0_PCH_TX_C_DP<7:0>";
8"DMI_CPU0_PCH_RX_C_DN<7:0>";
9"DMI_CPU0_PCH_TX_C_DN<7>";
10"DMI_CPU0_PCH_TX_DN<7>";
11"DMI_CPU0_PCH_RX_DN<6>";
12"DMI_CPU0_PCH_RX_C_DN<1>";
13"DMI_CPU0_PCH_RX_C_DP<1>";
14"DMI_CPU0_PCH_TX_DN<0>";
15"DMI_CPU0_PCH_TX_C_DP<2>";
16"DMI_CPU0_PCH_TX_C_DN<1>";
17"DMI_CPU0_PCH_TX_C_DP<1>";
18"DMI_CPU0_PCH_TX_C_DP<0>";
19"DMI_CPU0_PCH_RX_DN<1>";
20"DMI_CPU0_PCH_RX_C_DP<4>";
21"DMI_CPU0_PCH_RX_C_DP<2>";
22"DMI_CPU0_PCH_RX_DN<5>";
23"DMI_CPU0_PCH_RX_DP<5>";
24"DMI_CPU0_PCH_RX_C_DN<4>";
25"DMI_CPU0_PCH_RX_C_DN<0>";
26"DMI_CPU0_PCH_RX_C_DN<3>";
27"DMI_CPU0_PCH_RX_C_DP<3>";
28"DMI_CPU0_PCH_RX_DP<4>";
29"DMI_CPU0_PCH_TX_DP<2>";
30"DMI_CPU0_PCH_RX_C_DN<7>";
31"DMI_CPU0_PCH_RX_C_DP<7>";
32"DMI_CPU0_PCH_RX_C_DN<6>";
33"DMI_CPU0_PCH_RX_C_DP<6>";
34"DMI_CPU0_PCH_RX_C_DN<5>";
35"DMI_CPU0_PCH_RX_DP<2>";
36"DMI_CPU0_PCH_TX_DN<1>";
37"DMI_CPU0_PCH_TX_DP<1>";
38"DMI_CPU0_PCH_RX_DN<2>";
39"DMI_CPU0_PCH_RX_DN<3>";
40"DMI_CPU0_PCH_RX_C_DN<2>";
41"DMI_CPU0_PCH_RX_DN<4>";
42"DMI_CPU0_PCH_RX_DP<7>";
43"DMI_CPU0_PCH_RX_DN<7>";
44"DMI_CPU0_PCH_RX_C_DP<5>";
45"DMI_CPU0_PCH_TX_DP<0>";
46"DMI_CPU0_PCH_TX_C_DN<0>";
47"DMI_CPU0_PCH_TX_C_DN<6>";
48"DMI_CPU0_PCH_TX_C_DP<6>";
49"DMI_CPU0_PCH_TX_C_DP<5>";
50"DMI_CPU0_PCH_TX_C_DP<7>";
51"DMI_CPU0_PCH_TX_C_DN<5>";
52"DMI_CPU0_PCH_TX_C_DP<3>";
53"DMI_CPU0_PCH_TX_C_DP<4>";
54"DMI_CPU0_PCH_TX_C_DN<3>";
55"DMI_CPU0_PCH_TX_C_DN<4>";
56"DMI_CPU0_PCH_TX_C_DN<2>";
57"DMI_CPU0_PCH_TX_DN<6>";
58"DMI_CPU0_PCH_TX_DP<7>";
59"DMI_CPU0_PCH_TX_DP<3>";
60"DMI_CPU0_PCH_TX_DP<4>";
61"DMI_CPU0_PCH_TX_DN<4>";
62"DMI_CPU0_PCH_TX_DN<2>";
63"DMI_CPU0_PCH_TX_DN<3>";
64"DMI_CPU0_PCH_TX_DP<5>";
65"DMI_CPU0_PCH_TX_DN<5>";
66"DMI_CPU0_PCH_RX_DP<6>";
67"DMI_CPU0_PCH_RX_DP<3>";
68"DMI_CPU0_PCH_RX_DP<1>";
69"DMI_CPU0_PCH_RX_DN<0>";
70"DMI_CPU0_PCH_RX_DP<0>";
71"DMI_CPU0_PCH_RX_C_DP<0>";
72"DMI_CPU0_PCH_TX_DP<6>";
%"TAP"
"1","(-1700,725)","2","standard","I10";
;
CDS_LIB"standard"
BODY_TYPE"PLUMBING"
HDL_TAP"TRUE";
"B \NAC \NWC"1;
"S \NAC"
BN"3"59;
%"TAP"
"1","(25,-1475)","0","standard","I100";
;
CDS_LIB"standard"
BODY_TYPE"PLUMBING"
HDL_TAP"TRUE";
"B \NAC \NWC"2;
"S \NAC"
BN"7"31;
%"TAP"
"1","(25,-1675)","0","standard","I101";
;
CDS_LIB"standard"
BODY_TYPE"PLUMBING"
HDL_TAP"TRUE";
"B \NAC \NWC"2;
"S \NAC"
BN"6"33;
%"TAP"
"1","(25,-1875)","0","standard","I102";
;
CDS_LIB"standard"
BODY_TYPE"PLUMBING"
HDL_TAP"TRUE";
"B \NAC \NWC"2;
"S \NAC"
BN"5"44;
%"TAP"
"1","(-175,-1825)","0","standard","I103";
;
CDS_LIB"standard"
BODY_TYPE"PLUMBING"
HDL_TAP"TRUE";
"B \NAC \NWC"8;
"S \NAC"
BN"5"34;
%"TAP"
"1","(-175,-1625)","0","standard","I104";
;
CDS_LIB"standard"
BODY_TYPE"PLUMBING"
HDL_TAP"TRUE";
"B \NAC \NWC"8;
"S \NAC"
BN"6"32;
%"TAP"
"1","(25,-2075)","0","standard","I105";
;
CDS_LIB"standard"
BODY_TYPE"PLUMBING"
HDL_TAP"TRUE";
"B \NAC \NWC"2;
"S \NAC"
BN"4"20;
%"TAP"
"1","(25,-2475)","0","standard","I106";
;
CDS_LIB"standard"
BODY_TYPE"PLUMBING"
HDL_TAP"TRUE";
"B \NAC \NWC"2;
"S \NAC"
BN"2"21;
%"TAP"
"1","(25,-2275)","0","standard","I107";
;
CDS_LIB"standard"
BODY_TYPE"PLUMBING"
HDL_TAP"TRUE";
"B \NAC \NWC"2;
"S \NAC"
BN"3"27;
%"TAP"
"1","(-175,-2025)","0","standard","I108";
;
CDS_LIB"standard"
BODY_TYPE"PLUMBING"
HDL_TAP"TRUE";
"B \NAC \NWC"8;
"S \NAC"
BN"4"24;
%"TAP"
"1","(-175,-2425)","0","standard","I109";
;
CDS_LIB"standard"
BODY_TYPE"PLUMBING"
HDL_TAP"TRUE";
"B \NAC \NWC"8;
"S \NAC"
BN"2"40;
%"TAP"
"1","(-1700,925)","2","standard","I11";
;
CDS_LIB"standard"
BODY_TYPE"PLUMBING"
HDL_TAP"TRUE";
"B \NAC \NWC"1;
"S \NAC"
BN"4"60;
%"TAP"
"1","(-175,-2225)","0","standard","I110";
;
CDS_LIB"standard"
BODY_TYPE"PLUMBING"
HDL_TAP"TRUE";
"B \NAC \NWC"8;
"S \NAC"
BN"3"26;
%"TAP"
"1","(25,-2675)","0","standard","I111";
;
CDS_LIB"standard"
BODY_TYPE"PLUMBING"
HDL_TAP"TRUE";
"B \NAC \NWC"2;
"S \NAC"
BN"1"13;
%"TAP"
"1","(25,-2875)","0","standard","I112";
;
CDS_LIB"standard"
BODY_TYPE"PLUMBING"
HDL_TAP"TRUE";
"B \NAC \NWC"2;
"S \NAC"
BN"0"71;
%"Q_CAP_DIFFBUS"
"2","(-725,-1425)","2","pure_quanta","I113";
;
PART_NUMBER"SP_CH4221MEE01"
VALUE"DIFF BUS_0.22UF"
$LOCATION"C155"
TOLERANCE"20%"
PACK_TYPE"C0201"
MATERIAL"X6S"
VOLTAGE"6.3V"
CDS_LIB"pure_quanta"
CDS_LMAN_SYM_OUTLINE"-25,50,25,-50"
PIN_NAMES_ROTATE"TRUE"
$LOCATION"C155"
CDS_LOCATION"C155"
$SEC"1"
CDS_SEC"1";
"2"
$PN"2"43;
"1"
$PN"1"30;
%"Q_CAP_DIFFBUS"
"2","(-725,-1475)","2","pure_quanta","I114";
;
PART_NUMBER"SP_CH4221MEE01"
VALUE"DIFF BUS_0.22UF"
$LOCATION"C156"
TOLERANCE"20%"
PACK_TYPE"C0201"
MATERIAL"X6S"
VOLTAGE"6.3V"
CDS_LMAN_SYM_OUTLINE"-25,50,25,-50"
CDS_LIB"pure_quanta"
PIN_NAMES_ROTATE"TRUE"
$LOCATION"C156"
CDS_LOCATION"C156"
$SEC"1"
CDS_SEC"1";
"2"
$PN"2"42;
"1"
$PN"1"31;
%"Q_CAP_DIFFBUS"
"2","(-725,-1625)","2","pure_quanta","I115";
;
PART_NUMBER"SP_CH4221MEE01"
VALUE"DIFF BUS_0.22UF"
$LOCATION"C157"
TOLERANCE"20%"
PACK_TYPE"C0201"
MATERIAL"X6S"
VOLTAGE"6.3V"
CDS_LMAN_SYM_OUTLINE"-25,50,25,-50"
CDS_LIB"pure_quanta"
PIN_NAMES_ROTATE"TRUE"
$LOCATION"C157"
CDS_LOCATION"C157"
$SEC"1"
CDS_SEC"1";
"2"
$PN"2"11;
"1"
$PN"1"32;
%"Q_CAP_DIFFBUS"
"2","(-725,-1675)","2","pure_quanta","I116";
;
PART_NUMBER"SP_CH4221MEE01"
VALUE"DIFF BUS_0.22UF"
$LOCATION"C158"
TOLERANCE"20%"
PACK_TYPE"C0201"
MATERIAL"X6S"
VOLTAGE"6.3V"
CDS_LMAN_SYM_OUTLINE"-25,50,25,-50"
CDS_LIB"pure_quanta"
PIN_NAMES_ROTATE"TRUE"
$LOCATION"C158"
CDS_LOCATION"C158"
$SEC"1"
CDS_SEC"1";
"2"
$PN"2"66;
"1"
$PN"1"33;
%"Q_CAP_DIFFBUS"
"2","(-725,-1825)","2","pure_quanta","I117";
;
PART_NUMBER"SP_CH4221MEE01"
VALUE"DIFF BUS_0.22UF"
$LOCATION"C159"
TOLERANCE"20%"
PACK_TYPE"C0201"
MATERIAL"X6S"
VOLTAGE"6.3V"
CDS_LMAN_SYM_OUTLINE"-25,50,25,-50"
CDS_LIB"pure_quanta"
PIN_NAMES_ROTATE"TRUE"
$LOCATION"C159"
CDS_LOCATION"C159"
$SEC"1"
CDS_SEC"1";
"2"
$PN"2"22;
"1"
$PN"1"34;
%"Q_CAP_DIFFBUS"
"2","(-725,-1875)","2","pure_quanta","I118";
;
PART_NUMBER"SP_CH4221MEE01"
VALUE"DIFF BUS_0.22UF"
$LOCATION"C160"
TOLERANCE"20%"
PACK_TYPE"C0201"
MATERIAL"X6S"
VOLTAGE"6.3V"
CDS_LMAN_SYM_OUTLINE"-25,50,25,-50"
CDS_LIB"pure_quanta"
PIN_NAMES_ROTATE"TRUE"
$LOCATION"C160"
CDS_LOCATION"C160"
$SEC"1"
CDS_SEC"1";
"2"
$PN"2"23;
"1"
$PN"1"44;
%"Q_CAP_DIFFBUS"
"2","(-725,-2025)","2","pure_quanta","I119";
;
PART_NUMBER"SP_CH4221MEE01"
VALUE"DIFF BUS_0.22UF"
$LOCATION"C161"
TOLERANCE"20%"
PACK_TYPE"C0201"
MATERIAL"X6S"
VOLTAGE"6.3V"
CDS_LMAN_SYM_OUTLINE"-25,50,25,-50"
CDS_LIB"pure_quanta"
PIN_NAMES_ROTATE"TRUE"
$LOCATION"C161"
CDS_LOCATION"C161"
$SEC"1"
CDS_SEC"1";
"2"
$PN"2"41;
"1"
$PN"1"24;
%"TAP"
"1","(-1450,575)","2","standard","I12";
;
CDS_LIB"standard"
BODY_TYPE"PLUMBING"
HDL_TAP"TRUE";
"B \NAC \NWC"5;
"S \NAC"
BN"2"62;
%"Q_CAP_DIFFBUS"
"2","(-725,-2075)","2","pure_quanta","I120";
;
PART_NUMBER"SP_CH4221MEE01"
VALUE"DIFF BUS_0.22UF"
$LOCATION"C162"
TOLERANCE"20%"
PACK_TYPE"C0201"
MATERIAL"X6S"
VOLTAGE"6.3V"
CDS_LMAN_SYM_OUTLINE"-25,50,25,-50"
CDS_LIB"pure_quanta"
PIN_NAMES_ROTATE"TRUE"
$LOCATION"C162"
CDS_LOCATION"C162"
$SEC"1"
CDS_SEC"1";
"2"
$PN"2"28;
"1"
$PN"1"20;
%"Q_CAP_DIFFBUS"
"2","(-725,-2225)","2","pure_quanta","I121";
;
PART_NUMBER"SP_CH4221MEE01"
VALUE"DIFF BUS_0.22UF"
$LOCATION"C163"
TOLERANCE"20%"
PACK_TYPE"C0201"
MATERIAL"X6S"
VOLTAGE"6.3V"
CDS_LIB"pure_quanta"
CDS_LMAN_SYM_OUTLINE"-25,50,25,-50"
PIN_NAMES_ROTATE"TRUE"
$LOCATION"C163"
CDS_LOCATION"C163"
$SEC"1"
CDS_SEC"1";
"2"
$PN"2"39;
"1"
$PN"1"26;
%"Q_CAP_DIFFBUS"
"2","(-725,-2275)","2","pure_quanta","I122";
;
PART_NUMBER"SP_CH4221MEE01"
VALUE"DIFF BUS_0.22UF"
$LOCATION"C164"
TOLERANCE"20%"
PACK_TYPE"C0201"
MATERIAL"X6S"
VOLTAGE"6.3V"
CDS_LIB"pure_quanta"
CDS_LMAN_SYM_OUTLINE"-25,50,25,-50"
PIN_NAMES_ROTATE"TRUE"
$LOCATION"C164"
CDS_LOCATION"C164"
$SEC"1"
CDS_SEC"1";
"2"
$PN"2"67;
"1"
$PN"1"27;
%"Q_CAP_DIFFBUS"
"2","(-725,-2425)","2","pure_quanta","I123";
;
PART_NUMBER"SP_CH4221MEE01"
VALUE"DIFF BUS_0.22UF"
$LOCATION"C165"
TOLERANCE"20%"
PACK_TYPE"C0201"
MATERIAL"X6S"
VOLTAGE"6.3V"
CDS_LMAN_SYM_OUTLINE"-25,50,25,-50"
CDS_LIB"pure_quanta"
PIN_NAMES_ROTATE"TRUE"
$LOCATION"C165"
CDS_LOCATION"C165"
$SEC"1"
CDS_SEC"1";
"2"
$PN"2"38;
"1"
$PN"1"40;
%"Q_CAP_DIFFBUS"
"2","(-725,-2475)","2","pure_quanta","I124";
;
PART_NUMBER"SP_CH4221MEE01"
VALUE"DIFF BUS_0.22UF"
$LOCATION"C166"
TOLERANCE"20%"
PACK_TYPE"C0201"
MATERIAL"X6S"
VOLTAGE"6.3V"
CDS_LMAN_SYM_OUTLINE"-25,50,25,-50"
CDS_LIB"pure_quanta"
PIN_NAMES_ROTATE"TRUE"
$LOCATION"C166"
CDS_LOCATION"C166"
$SEC"1"
CDS_SEC"1";
"2"
$PN"2"35;
"1"
$PN"1"21;
%"Q_CAP_DIFFBUS"
"2","(-725,-2675)","2","pure_quanta","I125";
;
PART_NUMBER"SP_CH4221MEE01"
VALUE"DIFF BUS_0.22UF"
$LOCATION"C168"
TOLERANCE"20%"
PACK_TYPE"C0201"
MATERIAL"X6S"
VOLTAGE"6.3V"
CDS_LMAN_SYM_OUTLINE"-25,50,25,-50"
CDS_LIB"pure_quanta"
PIN_NAMES_ROTATE"TRUE"
$LOCATION"C168"
CDS_LOCATION"C168"
$SEC"1"
CDS_SEC"1";
"2"
$PN"2"68;
"1"
$PN"1"13;
%"Q_CAP_DIFFBUS"
"2","(-725,-2625)","2","pure_quanta","I126";
;
PART_NUMBER"SP_CH4221MEE01"
VALUE"DIFF BUS_0.22UF"
$LOCATION"C167"
TOLERANCE"20%"
PACK_TYPE"C0201"
MATERIAL"X6S"
VOLTAGE"6.3V"
CDS_LIB"pure_quanta"
CDS_LMAN_SYM_OUTLINE"-25,50,25,-50"
PIN_NAMES_ROTATE"TRUE"
$LOCATION"C167"
CDS_LOCATION"C167"
$SEC"1"
CDS_SEC"1";
"2"
$PN"2"19;
"1"
$PN"1"12;
%"Q_CAP_DIFFBUS"
"2","(-725,-2825)","2","pure_quanta","I127";
;
PART_NUMBER"SP_CH4221MEE01"
VALUE"DIFF BUS_0.22UF"
$LOCATION"C169"
TOLERANCE"20%"
PACK_TYPE"C0201"
MATERIAL"X6S"
VOLTAGE"6.3V"
CDS_LMAN_SYM_OUTLINE"-25,50,25,-50"
CDS_LIB"pure_quanta"
PIN_NAMES_ROTATE"TRUE"
$LOCATION"C169"
CDS_LOCATION"C169"
$SEC"1"
CDS_SEC"1";
"2"
$PN"2"69;
"1"
$PN"1"25;
%"Q_CAP_DIFFBUS"
"2","(-725,-2875)","2","pure_quanta","I128";
;
PART_NUMBER"SP_CH4221MEE01"
VALUE"DIFF BUS_0.22UF"
$LOCATION"C170"
TOLERANCE"20%"
PACK_TYPE"C0201"
MATERIAL"X6S"
VOLTAGE"6.3V"
CDS_LMAN_SYM_OUTLINE"-25,50,25,-50"
CDS_LIB"pure_quanta"
PIN_NAMES_ROTATE"TRUE"
$LOCATION"C170"
CDS_LOCATION"C170"
$SEC"1"
CDS_SEC"1";
"2"
$PN"2"70;
"1"
$PN"1"71;
%"TAP"
"1","(-1450,-1425)","2","standard","I129";
;
CDS_LIB"standard"
BODY_TYPE"PLUMBING"
HDL_TAP"TRUE";
"B \NAC \NWC"4;
"S \NAC"
BN"7"43;
%"TAP"
"1","(-1450,775)","2","standard","I13";
;
CDS_LIB"standard"
BODY_TYPE"PLUMBING"
HDL_TAP"TRUE";
"B \NAC \NWC"5;
"S \NAC"
BN"3"63;
%"TAP"
"1","(-1450,-1625)","2","standard","I130";
;
CDS_LIB"standard"
BODY_TYPE"PLUMBING"
HDL_TAP"TRUE";
"B \NAC \NWC"4;
"S \NAC"
BN"6"11;
%"TAP"
"1","(-1700,-1475)","2","standard","I131";
;
CDS_LIB"standard"
BODY_TYPE"PLUMBING"
HDL_TAP"TRUE";
"B \NAC \NWC"3;
"S \NAC"
BN"7"42;
%"TAP"
"1","(-1450,-1825)","2","standard","I132";
;
CDS_LIB"standard"
BODY_TYPE"PLUMBING"
HDL_TAP"TRUE";
"B \NAC \NWC"4;
"S \NAC"
BN"5"22;
%"TAP"
"1","(-1700,-1875)","2","standard","I133";
;
CDS_LIB"standard"
BODY_TYPE"PLUMBING"
HDL_TAP"TRUE";
"B \NAC \NWC"3;
"S \NAC"
BN"5"23;
%"TAP"
"1","(-1700,-1675)","2","standard","I134";
;
CDS_LIB"standard"
BODY_TYPE"PLUMBING"
HDL_TAP"TRUE";
"B \NAC \NWC"3;
"S \NAC"
BN"6"66;
%"TAP"
"1","(-1450,-2025)","2","standard","I135";
;
CDS_LIB"standard"
BODY_TYPE"PLUMBING"
HDL_TAP"TRUE";
"B \NAC \NWC"4;
"S \NAC"
BN"4"41;
%"TAP"
"1","(-1450,-2225)","2","standard","I136";
;
CDS_LIB"standard"
BODY_TYPE"PLUMBING"
HDL_TAP"TRUE";
"B \NAC \NWC"4;
"S \NAC"
BN"3"39;
%"TAP"
"1","(-1450,-2425)","2","standard","I137";
;
CDS_LIB"standard"
BODY_TYPE"PLUMBING"
HDL_TAP"TRUE";
"B \NAC \NWC"4;
"S \NAC"
BN"2"38;
%"TAP"
"1","(-1700,-2075)","2","standard","I138";
;
CDS_LIB"standard"
BODY_TYPE"PLUMBING"
HDL_TAP"TRUE";
"B \NAC \NWC"3;
"S \NAC"
BN"4"28;
%"TAP"
"1","(-1700,-2275)","2","standard","I139";
;
CDS_LIB"standard"
BODY_TYPE"PLUMBING"
HDL_TAP"TRUE";
"B \NAC \NWC"3;
"S \NAC"
BN"3"67;
%"TAP"
"1","(-1700,1125)","2","standard","I14";
;
CDS_LIB"standard"
BODY_TYPE"PLUMBING"
HDL_TAP"TRUE";
"B \NAC \NWC"1;
"S \NAC"
BN"5"64;
%"TAP"
"1","(-1700,-2475)","2","standard","I140";
;
CDS_LIB"standard"
BODY_TYPE"PLUMBING"
HDL_TAP"TRUE";
"B \NAC \NWC"3;
"S \NAC"
BN"2"35;
%"TAP"
"1","(-1450,-2625)","2","standard","I141";
;
CDS_LIB"standard"
BODY_TYPE"PLUMBING"
HDL_TAP"TRUE";
"B \NAC \NWC"4;
"S \NAC"
BN"1"19;
%"TAP"
"1","(-1450,-2825)","2","standard","I142";
;
CDS_LIB"standard"
BODY_TYPE"PLUMBING"
HDL_TAP"TRUE";
"B \NAC \NWC"4;
"S \NAC"
BN"0"69;
%"TAP"
"1","(-1700,-2675)","2","standard","I143";
;
CDS_LIB"standard"
BODY_TYPE"PLUMBING"
HDL_TAP"TRUE";
"B \NAC \NWC"3;
"S \NAC"
BN"1"68;
%"TAP"
"1","(-1700,-2875)","2","standard","I144";
;
CDS_LIB"standard"
BODY_TYPE"PLUMBING"
HDL_TAP"TRUE";
"B \NAC \NWC"3;
"S \NAC"
BN"0"70;
%"TAP"
"1","(-1700,1325)","2","standard","I15";
;
CDS_LIB"standard"
BODY_TYPE"PLUMBING"
HDL_TAP"TRUE";
"B \NAC \NWC"1;
"S \NAC"
BN"6"72;
%"TAP"
"1","(-1450,975)","2","standard","I16";
;
CDS_LIB"standard"
BODY_TYPE"PLUMBING"
HDL_TAP"TRUE";
"B \NAC \NWC"5;
"S \NAC"
BN"4"61;
%"TAP"
"1","(-1450,1175)","2","standard","I17";
;
CDS_LIB"standard"
BODY_TYPE"PLUMBING"
HDL_TAP"TRUE";
"B \NAC \NWC"5;
"S \NAC"
BN"5"65;
%"TAP"
"1","(-1450,1375)","2","standard","I18";
;
CDS_LIB"standard"
BODY_TYPE"PLUMBING"
HDL_TAP"TRUE";
"B \NAC \NWC"5;
"S \NAC"
BN"6"57;
%"TAP"
"1","(-1700,1525)","2","standard","I19";
;
CDS_LIB"standard"
BODY_TYPE"PLUMBING"
HDL_TAP"TRUE";
"B \NAC \NWC"1;
"S \NAC"
BN"7"58;
%"TAP"
"1","(-1450,1575)","2","standard","I20";
;
CDS_LIB"standard"
BODY_TYPE"PLUMBING"
HDL_TAP"TRUE";
"B \NAC \NWC"5;
"S \NAC"
BN"7"10;
%"Q_CAP_DIFFBUS"
"2","(-725,175)","2","pure_quanta","I21";
;
PART_NUMBER"SP_CH4221MEE01"
VALUE"DIFF BUS_0.22UF"
$LOCATION"C153"
TOLERANCE"20%"
PACK_TYPE"C0201"
MATERIAL"X6S"
VOLTAGE"6.3V"
CDS_LMAN_SYM_OUTLINE"-25,50,25,-50"
CDS_LIB"pure_quanta"
PIN_NAMES_ROTATE"TRUE"
$LOCATION"C153"
CDS_LOCATION"C153"
$SEC"1"
CDS_SEC"1";
"2"
$PN"2"14;
"1"
$PN"1"46;
%"Q_CAP_DIFFBUS"
"2","(-725,125)","2","pure_quanta","I22";
;
PART_NUMBER"SP_CH4221MEE01"
VALUE"DIFF BUS_0.22UF"
$LOCATION"C154"
TOLERANCE"20%"
PACK_TYPE"C0201"
MATERIAL"X6S"
VOLTAGE"6.3V"
CDS_LMAN_SYM_OUTLINE"-25,50,25,-50"
CDS_LIB"pure_quanta"
PIN_NAMES_ROTATE"TRUE"
$LOCATION"C154"
CDS_LOCATION"C154"
$SEC"1"
CDS_SEC"1";
"2"
$PN"2"45;
"1"
$PN"1"18;
%"Q_CAP_DIFFBUS"
"2","(-725,325)","2","pure_quanta","I23";
;
PART_NUMBER"SP_CH4221MEE01"
VALUE"DIFF BUS_0.22UF"
$LOCATION"C152"
TOLERANCE"20%"
PACK_TYPE"C0201"
MATERIAL"X6S"
VOLTAGE"6.3V"
CDS_LMAN_SYM_OUTLINE"-25,50,25,-50"
CDS_LIB"pure_quanta"
PIN_NAMES_ROTATE"TRUE"
$LOCATION"C152"
CDS_LOCATION"C152"
$SEC"1"
CDS_SEC"1";
"2"
$PN"2"37;
"1"
$PN"1"17;
%"Q_CAP_DIFFBUS"
"2","(-725,375)","2","pure_quanta","I24";
;
PART_NUMBER"SP_CH4221MEE01"
VALUE"DIFF BUS_0.22UF"
$LOCATION"C151"
TOLERANCE"20%"
PACK_TYPE"C0201"
MATERIAL"X6S"
VOLTAGE"6.3V"
CDS_LIB"pure_quanta"
CDS_LMAN_SYM_OUTLINE"-25,50,25,-50"
PIN_NAMES_ROTATE"TRUE"
$LOCATION"C151"
CDS_LOCATION"C151"
$SEC"1"
CDS_SEC"1";
"2"
$PN"2"36;
"1"
$PN"1"16;
%"Q_CAP_DIFFBUS"
"2","(-725,575)","2","pure_quanta","I25";
;
PART_NUMBER"SP_CH4221MEE01"
VALUE"DIFF BUS_0.22UF"
$LOCATION"C149"
TOLERANCE"20%"
PACK_TYPE"C0201"
MATERIAL"X6S"
VOLTAGE"6.3V"
CDS_LMAN_SYM_OUTLINE"-25,50,25,-50"
CDS_LIB"pure_quanta"
PIN_NAMES_ROTATE"TRUE"
$LOCATION"C149"
CDS_LOCATION"C149"
$SEC"1"
CDS_SEC"1";
"2"
$PN"2"62;
"1"
$PN"1"56;
%"Q_CAP_DIFFBUS"
"2","(-725,525)","2","pure_quanta","I26";
;
PART_NUMBER"SP_CH4221MEE01"
VALUE"DIFF BUS_0.22UF"
$LOCATION"C150"
TOLERANCE"20%"
PACK_TYPE"C0201"
MATERIAL"X6S"
VOLTAGE"6.3V"
CDS_LMAN_SYM_OUTLINE"-25,50,25,-50"
CDS_LIB"pure_quanta"
PIN_NAMES_ROTATE"TRUE"
$LOCATION"C150"
CDS_LOCATION"C150"
$SEC"1"
CDS_SEC"1";
"2"
$PN"2"29;
"1"
$PN"1"15;
%"Q_CAP_DIFFBUS"
"2","(-725,725)","2","pure_quanta","I27";
;
PART_NUMBER"SP_CH4221MEE01"
VALUE"DIFF BUS_0.22UF"
$LOCATION"C148"
TOLERANCE"20%"
PACK_TYPE"C0201"
MATERIAL"X6S"
VOLTAGE"6.3V"
CDS_LIB"pure_quanta"
CDS_LMAN_SYM_OUTLINE"-25,50,25,-50"
PIN_NAMES_ROTATE"TRUE"
$LOCATION"C148"
CDS_LOCATION"C148"
$SEC"1"
CDS_SEC"1";
"2"
$PN"2"59;
"1"
$PN"1"52;
%"Q_CAP_DIFFBUS"
"2","(-725,775)","2","pure_quanta","I28";
;
PART_NUMBER"SP_CH4221MEE01"
VALUE"DIFF BUS_0.22UF"
$LOCATION"C147"
TOLERANCE"20%"
PACK_TYPE"C0201"
MATERIAL"X6S"
VOLTAGE"6.3V"
CDS_LIB"pure_quanta"
CDS_LMAN_SYM_OUTLINE"-25,50,25,-50"
PIN_NAMES_ROTATE"TRUE"
$LOCATION"C147"
CDS_LOCATION"C147"
$SEC"1"
CDS_SEC"1";
"2"
$PN"2"63;
"1"
$PN"1"54;
%"Q_CAP_DIFFBUS"
"2","(-725,925)","2","pure_quanta","I29";
;
PART_NUMBER"SP_CH4221MEE01"
VALUE"DIFF BUS_0.22UF"
$LOCATION"C146"
TOLERANCE"20%"
PACK_TYPE"C0201"
MATERIAL"X6S"
VOLTAGE"6.3V"
CDS_LMAN_SYM_OUTLINE"-25,50,25,-50"
CDS_LIB"pure_quanta"
PIN_NAMES_ROTATE"TRUE"
$LOCATION"C146"
CDS_LOCATION"C146"
$SEC"1"
CDS_SEC"1";
"2"
$PN"2"60;
"1"
$PN"1"53;
%"Q_CAP_DIFFBUS"
"2","(-725,975)","2","pure_quanta","I30";
;
PART_NUMBER"SP_CH4221MEE01"
VALUE"DIFF BUS_0.22UF"
$LOCATION"C145"
TOLERANCE"20%"
PACK_TYPE"C0201"
MATERIAL"X6S"
VOLTAGE"6.3V"
CDS_LMAN_SYM_OUTLINE"-25,50,25,-50"
CDS_LIB"pure_quanta"
PIN_NAMES_ROTATE"TRUE"
$LOCATION"C145"
CDS_LOCATION"C145"
$SEC"1"
CDS_SEC"1";
"2"
$PN"2"61;
"1"
$PN"1"55;
%"Q_CAP_DIFFBUS"
"2","(-725,1125)","2","pure_quanta","I31";
;
PART_NUMBER"SP_CH4221MEE01"
VALUE"DIFF BUS_0.22UF"
$LOCATION"C144"
TOLERANCE"20%"
PACK_TYPE"C0201"
MATERIAL"X6S"
VOLTAGE"6.3V"
CDS_LMAN_SYM_OUTLINE"-25,50,25,-50"
CDS_LIB"pure_quanta"
PIN_NAMES_ROTATE"TRUE"
$LOCATION"C144"
CDS_LOCATION"C144"
$SEC"1"
CDS_SEC"1";
"2"
$PN"2"64;
"1"
$PN"1"49;
%"Q_CAP_DIFFBUS"
"2","(-725,1175)","2","pure_quanta","I32";
;
PART_NUMBER"SP_CH4221MEE01"
VALUE"DIFF BUS_0.22UF"
$LOCATION"C143"
TOLERANCE"20%"
PACK_TYPE"C0201"
MATERIAL"X6S"
VOLTAGE"6.3V"
CDS_LMAN_SYM_OUTLINE"-25,50,25,-50"
CDS_LIB"pure_quanta"
PIN_NAMES_ROTATE"TRUE"
$LOCATION"C143"
CDS_LOCATION"C143"
$SEC"1"
CDS_SEC"1";
"2"
$PN"2"65;
"1"
$PN"1"51;
%"Q_CAP_DIFFBUS"
"2","(-725,1325)","2","pure_quanta","I33";
;
PART_NUMBER"SP_CH4221MEE01"
VALUE"DIFF BUS_0.22UF"
$LOCATION"C142"
TOLERANCE"20%"
PACK_TYPE"C0201"
MATERIAL"X6S"
VOLTAGE"6.3V"
CDS_LMAN_SYM_OUTLINE"-25,50,25,-50"
CDS_LIB"pure_quanta"
PIN_NAMES_ROTATE"TRUE"
$LOCATION"C142"
CDS_LOCATION"C142"
$SEC"1"
CDS_SEC"1";
"2"
$PN"2"72;
"1"
$PN"1"48;
%"Q_CAP_DIFFBUS"
"2","(-725,1375)","2","pure_quanta","I34";
;
PART_NUMBER"SP_CH4221MEE01"
VALUE"DIFF BUS_0.22UF"
$LOCATION"C141"
TOLERANCE"20%"
PACK_TYPE"C0201"
MATERIAL"X6S"
VOLTAGE"6.3V"
CDS_LMAN_SYM_OUTLINE"-25,50,25,-50"
CDS_LIB"pure_quanta"
PIN_NAMES_ROTATE"TRUE"
$LOCATION"C141"
CDS_LOCATION"C141"
$SEC"1"
CDS_SEC"1";
"2"
$PN"2"57;
"1"
$PN"1"47;
%"Q_CAP_DIFFBUS"
"2","(-725,1575)","2","pure_quanta","I35";
;
PART_NUMBER"SP_CH4221MEE01"
VALUE"DIFF BUS_0.22UF"
$LOCATION"C139"
PACK_TYPE"C0201"
MATERIAL"X6S"
VOLTAGE"6.3V"
CDS_LIB"pure_quanta"
CDS_LMAN_SYM_OUTLINE"-25,50,25,-50"
PIN_NAMES_ROTATE"TRUE"
TOLERANCE"20%"
$LOCATION"C139"
CDS_LOCATION"C139"
$SEC"1"
CDS_SEC"1";
"2"
$PN"2"10;
"1"
$PN"1"9;
%"Q_CAP_DIFFBUS"
"2","(-725,1525)","2","pure_quanta","I36";
;
PART_NUMBER"SP_CH4221MEE01"
VALUE"DIFF BUS_0.22UF"
$LOCATION"C1791"
TOLERANCE"20%"
PACK_TYPE"C0201"
MATERIAL"X6S"
VOLTAGE"6.3V"
CDS_LMAN_SYM_OUTLINE"-25,50,25,-50"
CDS_LIB"pure_quanta"
PIN_NAMES_ROTATE"TRUE"
CDS_LOCATION"C1791"
$SEC"1"
CDS_SEC"1";
"2"
$PN"2"58;
"1"
$PN"1"50;
%"TAP"
"1","(-1700,125)","2","standard","I5";
;
CDS_LIB"standard"
BODY_TYPE"PLUMBING"
HDL_TAP"TRUE";
"B \NAC \NWC"1;
"S \NAC"
BN"0"45;
%"TAP"
"1","(-1700,325)","2","standard","I6";
;
CDS_LIB"standard"
BODY_TYPE"PLUMBING"
HDL_TAP"TRUE";
"B \NAC \NWC"1;
"S \NAC"
BN"1"37;
%"TAP"
"1","(-1450,175)","2","standard","I7";
;
CDS_LIB"standard"
BODY_TYPE"PLUMBING"
HDL_TAP"TRUE";
"B \NAC \NWC"5;
"S \NAC"
BN"0"14;
%"TAP"
"1","(-175,1575)","0","standard","I76";
;
CDS_LIB"standard"
BODY_TYPE"PLUMBING"
HDL_TAP"TRUE";
"B \NAC \NWC"6;
"S \NAC"
BN"7"9;
%"TAP"
"1","(-175,1175)","0","standard","I77";
;
CDS_LIB"standard"
BODY_TYPE"PLUMBING"
HDL_TAP"TRUE";
"B \NAC \NWC"6;
"S \NAC"
BN"5"51;
%"TAP"
"1","(-175,1375)","0","standard","I78";
;
CDS_LIB"standard"
BODY_TYPE"PLUMBING"
HDL_TAP"TRUE";
"B \NAC \NWC"6;
"S \NAC"
BN"6"47;
%"TAP"
"1","(-175,775)","0","standard","I79";
;
CDS_LIB"standard"
BODY_TYPE"PLUMBING"
HDL_TAP"TRUE";
"B \NAC \NWC"6;
"S \NAC"
BN"3"54;
%"TAP"
"1","(-1450,375)","2","standard","I8";
;
CDS_LIB"standard"
BODY_TYPE"PLUMBING"
HDL_TAP"TRUE";
"B \NAC \NWC"5;
"S \NAC"
BN"1"36;
%"TAP"
"1","(-175,975)","0","standard","I80";
;
CDS_LIB"standard"
BODY_TYPE"PLUMBING"
HDL_TAP"TRUE";
"B \NAC \NWC"6;
"S \NAC"
BN"4"55;
%"TAP"
"1","(-175,575)","0","standard","I81";
;
CDS_LIB"standard"
BODY_TYPE"PLUMBING"
HDL_TAP"TRUE";
"B \NAC \NWC"6;
"S \NAC"
BN"2"56;
%"TAP"
"1","(-175,375)","0","standard","I82";
;
CDS_LIB"standard"
BODY_TYPE"PLUMBING"
HDL_TAP"TRUE";
"B \NAC \NWC"6;
"S \NAC"
BN"1"16;
%"TAP"
"1","(-175,175)","0","standard","I83";
;
CDS_LIB"standard"
BODY_TYPE"PLUMBING"
HDL_TAP"TRUE";
"B \NAC \NWC"6;
"S \NAC"
BN"0"46;
%"TAP"
"1","(25,125)","0","standard","I85";
;
CDS_LIB"standard"
BODY_TYPE"PLUMBING"
HDL_TAP"TRUE";
"B \NAC \NWC"7;
"S \NAC"
BN"0"18;
%"TAP"
"1","(25,325)","0","standard","I86";
;
CDS_LIB"standard"
BODY_TYPE"PLUMBING"
HDL_TAP"TRUE";
"B \NAC \NWC"7;
"S \NAC"
BN"1"17;
%"TAP"
"1","(25,525)","0","standard","I87";
;
CDS_LIB"standard"
BODY_TYPE"PLUMBING"
HDL_TAP"TRUE";
"B \NAC \NWC"7;
"S \NAC"
BN"2"15;
%"TAP"
"1","(25,725)","0","standard","I88";
;
CDS_LIB"standard"
BODY_TYPE"PLUMBING"
HDL_TAP"TRUE";
"B \NAC \NWC"7;
"S \NAC"
BN"3"52;
%"TAP"
"1","(25,925)","0","standard","I89";
;
CDS_LIB"standard"
BODY_TYPE"PLUMBING"
HDL_TAP"TRUE";
"B \NAC \NWC"7;
"S \NAC"
BN"4"53;
%"TAP"
"1","(-1700,525)","2","standard","I9";
;
CDS_LIB"standard"
BODY_TYPE"PLUMBING"
HDL_TAP"TRUE";
"B \NAC \NWC"1;
"S \NAC"
BN"2"29;
%"TAP"
"1","(25,1125)","0","standard","I90";
;
CDS_LIB"standard"
BODY_TYPE"PLUMBING"
HDL_TAP"TRUE";
"B \NAC \NWC"7;
"S \NAC"
BN"5"49;
%"TAP"
"1","(25,1325)","0","standard","I91";
;
CDS_LIB"standard"
BODY_TYPE"PLUMBING"
HDL_TAP"TRUE";
"B \NAC \NWC"7;
"S \NAC"
BN"6"48;
%"TAP"
"1","(25,1525)","0","standard","I92";
;
CDS_LIB"standard"
BODY_TYPE"PLUMBING"
HDL_TAP"TRUE";
"B \NAC \NWC"7;
"S \NAC"
BN"7"50;
%"TAP"
"1","(-175,-2625)","0","standard","I95";
;
CDS_LIB"standard"
BODY_TYPE"PLUMBING"
HDL_TAP"TRUE";
"B \NAC \NWC"8;
"S \NAC"
BN"1"12;
%"TAP"
"1","(-175,-2825)","0","standard","I96";
;
CDS_LIB"standard"
BODY_TYPE"PLUMBING"
HDL_TAP"TRUE";
"B \NAC \NWC"8;
"S \NAC"
BN"0"25;
%"TAP"
"1","(-175,-1425)","0","standard","I99";
;
CDS_LIB"standard"
BODY_TYPE"PLUMBING"
HDL_TAP"TRUE";
"B \NAC \NWC"8;
"S \NAC"
BN"7"30;
END.
